# Discovery_BOM.xlsx — Sheet1 (bom)
| BOM Discovery |  |  |  |  |  |  |  |  |
| Name | description | Type | rev | Sub assembly | Date | Supplier | Supplier ref | Qty |
| Door metal sheet |  | Metal sheet | B | Door |  | Constructor |  | 1 |
| Door locker |  | Accessories | A | Door |  | Southco | 62-42-301-3 | 1 |
| Hinge F6 leaf door |  | Accessories | B | Door |  | Southco | F6-1-1 | 2 |
| Rivet |  | Fastening hardware | A | Door |  | To define |  | 4 |
| Foam Pad |  | Accessories | A | Door |  | Radiospare |  | 1 |
| Side wall |  | Sheet metal | B | Side wall |  | Constructor |  | 2 |
| Wall Front right |  | Sheet metal | B | Casing |  | Constructor |  | 1 |
| Wall Front left |  | Sheet metal | B | Casing |  | Constructor |  | 1 |
| Wall back right |  | Sheet metal | B | Casing |  | Constructor |  | 1 |
| Wall back left |  | Sheet metal | B | Casing |  | Constructor |  | 1 |
| Back wall |  | Sheet metal | B | Casing |  | Constructor |  | 1 |
| Self clinching nut |  | Fastening hardware | A | Casing |  | PennEngineering | SP-M6-1 | 8 |
| Hinge F6 frame leaf |  | Accessories | B | Casing |  | Southco | F6-1-1 | 2 |
| Top |  | Sheet metal | B | Casing |  | Mass precision |  | 1 |
| Bottom |  | Sheet metal | B | Casing |  | Mass precision |  | 1 |
| Caster front |  | Accessories | A | Casing |  | ITEM |  | 2 |
| Caster Back |  | Accessories | A | Casing |  | ITEM |  | 2 |
| Horizontal support busbar |  | Sheet metal | B | Casing |  | Mass precision |  | 1 |
| Support server lock |  | Sheet metal | A | Casing |  | Mass precision |  | 5 |
| Support base left |  | Recertified hardware | A | Casing |  | ITRenew |  | 5 |
| Support base right |  | Recertified hardware | A | Casing |  | ITRenew |  | 5 |
| BusBar |  | Recertified hardware | A | Casing |  | ITRenew |  | 1 |
| Busbar lug cover |  | Recertified hardware | A | Casing |  | ITRenew |  | 1 |
| Adapter open rack V2 |  | Metal sheet | A | Mini cubby |  | Constructor |  | 1 |
| Wall break cubby |  | Recertified hardware | A | Mini cubby |  | ITRenew |  | 1 |
| Medusa cable |  | Recertified hardware | A | Mini cubby |  | ITRenew |  | 1 |
| Power board support |  | Sheet metal | B | Power board bloc |  | Constructor |  | 1 |
| Standoff |  | Fastening hardware | A | Power board bloc |  | PennEngineering | BSO4-M4-10 | 4 |
| Power board |  | Electronical board | B | Power board bloc |  | Constructor |  | 1 |
| PSU support |  | Sheet metal | B | PSU bloc |  | Constructor |  | 1 |
| PSU |  | Power | A | PSU bloc |  | Corsair | AX-1600i | 1 |
| Screw M6x8 panhead |  | Fastening hardware | A | Screw kit |  | To define | M6x8 | 8 |
| Countersunk screw M4x8 |  | Fastening hardware | A | Screw kit |  | To define | M4x8 | 6 |
| Screw M4x5 panhead |  | Fastening hardware | A | Screw kit |  | To define | M4x5 | 16 |
| PSU screw |  | Fastening hardware | A | Screw kit |  | To define |  | 4 |
| Screw M6x8 panhead for support |  | Recertified hardware | A | Screw kit |  | To define |  | 20 |
